# S9S_MB_2U (Grand Teton) — schematic netlist excerpt (pin names and nets, part order shuffled) for the footprints in the layout excerpt that follows; sources: Cadence DE-HDL packaged netlist, KiCad conversion of 03242023_DA0F0TMBIJ0_F0T_Motherboard_J_brd_V01_OCP.brd

PC197_P0_1  Q_CAP  22UF 16V 20% X6S  pkg C0805  page 275 : A = SW_P12V_PVCCINFAON_CPU0_FLT ; B = GND
R3807  Q_RES  0 5% CHIP  pkg 0402LF  page 162 : A = P3V3_OCP_UV_2_R1 ; B = P3V3_OCP_UV_2
R1395  Q_RES  33.2 1% CHIP  pkg 0402LF  page 185 : A = SPI_PCH_TPM_CS_N ; B = SPI_TPM_CS_N

(kicad_pcb
	(version 20260206)
	(generator "pcbnew")
	(generator_version "10.0")
	(general
		(thickness 1.6)
		(legacy_teardrops no)
	)
	(paper "A4")
	(title_block
		(title "03242023_DA0F0TMBIJ0_F0T_Motherboard_J_brd_V01_OCP.brd")
		(comment 1 "Grand Teton / footprints 5632-5634 of 6105")
	)
	(layers
		(0 "F.Cu" signal "TOP")
		(4 "In1.Cu" signal "GND")
		(6 "In2.Cu" signal "IN1")
		(8 "In3.Cu" signal "GND1")
		(10 "In4.Cu" signal "IN2")
		(12 "In5.Cu" signal "GND2")
		(14 "In6.Cu" signal "IN3")
		(16 "In7.Cu" signal "GND3")
		(18 "In8.Cu" signal "VCC")
		(20 "In9.Cu" signal "VCC1")
		(22 "In10.Cu" signal "GND4")
		(24 "In11.Cu" signal "IN4")
		(26 "In12.Cu" signal "GND5")
		(28 "In13.Cu" signal "IN5")
		(30 "In14.Cu" signal "GND6")
		(32 "In15.Cu" signal "IN6")
		(34 "In16.Cu" signal "GND7")
		(2 "B.Cu" signal "BOTTOM")
		(9 "F.Adhes" user "F.Adhesive")
		(11 "B.Adhes" user "B.Adhesive")
		(13 "F.Paste" user "Package Geometry/Pastemask Top")
		(15 "B.Paste" user "Package Geometry/Pastemask Bottom")
		(5 "F.SilkS" user "Ref Des/Silkscreen Top")
		(7 "B.SilkS" user "Ref Des/Silkscreen Bottom")
		(1 "F.Mask" user "Board Geometry/Soldermask Top")
		(3 "B.Mask" user "Board Geometry/Soldermask Bottom")
		(17 "Dwgs.User" user "User.Drawings")
		(19 "Cmts.User" user "User.Comments")
		(21 "Eco1.User" user "User.Eco1")
		(23 "Eco2.User" user "User.Eco2")
		(25 "Edge.Cuts" user "Board Geometry/Outline")
		(27 "Margin" user)
		(31 "F.CrtYd" user "Package Geometry/Place Bound Top")
		(29 "B.CrtYd" user "Package Geometry/Place Bound Bottom")
		(35 "F.Fab" user "Ref Des/Assembly Top")
		(33 "B.Fab" user "Ref Des/Assembly Bottom")
	)
	(footprint ""
		(layer "B.Cu")
		(at 332.543912 -31.386272 90)
		(property "Reference" "R1395"
			(at 0 0 90)
			(layer "B.SilkS")
			(hide yes)
			(effects
				(font
					(size 1.27 1.27)
				)
				(justify mirror)
			)
		)
		(property "Value" ""
			(at 0 0 90)
			(layer "B.Fab")
			(effects
				(font
					(size 1.27 1.27)
				)
				(justify mirror)
			)
		)
		(duplicate_pad_numbers_are_jumpers no)
		(fp_line
			(start 0.7874 -0.4064)
			(end -0.7874 -0.4064)
			(stroke
				(width 0.1524)
				(type default)
			)
			(layer "B.SilkS")
		)
		(fp_line
			(start -0.7874 -0.4064)
			(end -0.7874 0.4064)
			(stroke
				(width 0.1524)
				(type default)
			)
			(layer "B.SilkS")
		)
		(fp_line
			(start 0.7874 0.4064)
			(end 0.7874 -0.4064)
			(stroke
				(width 0.1524)
				(type default)
			)
			(layer "B.SilkS")
		)
		(fp_line
			(start -0.7874 0.4064)
			(end 0.7874 0.4064)
			(stroke
				(width 0.1524)
				(type default)
			)
			(layer "B.SilkS")
		)
		(fp_line
			(start 0.67945 -0.305054)
			(end 0.12065 -0.305054)
			(stroke
				(width 0.1)
				(type default)
			)
			(layer "B.Fab")
		)
		(fp_line
			(start 0.12065 -0.305054)
			(end 0.12065 -0.2794)
			(stroke
				(width 0.1)
				(type default)
			)
			(layer "B.Fab")
		)
		(fp_line
			(start -0.12065 -0.3048)
			(end -0.67945 -0.3048)
			(stroke
				(width 0.1)
				(type default)
			)
			(layer "B.Fab")
		)
		(fp_line
			(start -0.67945 -0.3048)
			(end -0.67945 0.3048)
			(stroke
				(width 0.1)
				(type default)
			)
			(layer "B.Fab")
		)
		(fp_line
			(start 0.12065 -0.2794)
			(end -0.12065 -0.2794)
			(stroke
				(width 0.1)
				(type default)
			)
			(layer "B.Fab")
		)
		(fp_line
			(start -0.12065 -0.2794)
			(end -0.12065 -0.3048)
			(stroke
				(width 0.1)
				(type default)
			)
			(layer "B.Fab")
		)
		(fp_line
			(start 0.12065 0.2794)
			(end 0.12065 0.3048)
			(stroke
				(width 0.1)
				(type default)
			)
			(layer "B.Fab")
		)
		(fp_line
			(start -0.120396 0.2794)
			(end 0.12065 0.2794)
			(stroke
				(width 0.1)
				(type default)
			)
			(layer "B.Fab")
		)
		(fp_line
			(start 0.67945 0.3048)
			(end 0.67945 -0.305054)
			(stroke
				(width 0.1)
				(type default)
			)
			(layer "B.Fab")
		)
		(fp_line
			(start 0.12065 0.3048)
			(end 0.67945 0.3048)
			(stroke
				(width 0.1)
				(type default)
			)
			(layer "B.Fab")
		)
		(fp_line
			(start -0.120396 0.3048)
			(end -0.120396 0.2794)
			(stroke
				(width 0.1)
				(type default)
			)
			(layer "B.Fab")
		)
		(fp_line
			(start -0.67945 0.3048)
			(end -0.120396 0.3048)
			(stroke
				(width 0.1)
				(type default)
			)
			(layer "B.Fab")
		)
		(pad "1" smd circle
			(at 0.40005 0 270)
			(size 0 0)
			(layers "B.Cu" "B.Mask" "B.Paste")
			(net "SPI_PCH_TPM_CS_N")
		)
		(pad "2" smd circle
			(at -0.40005 0 270)
			(size 0 0)
			(layers "B.Cu" "B.Mask" "B.Paste")
			(net "SPI_TPM_CS_N")
		)
	)
	(footprint ""
		(layer "B.Cu")
		(at 80.812132 -58.416698 90)
		(property "Reference" "R3807"
			(at 0 0 90)
			(layer "B.SilkS")
			(hide yes)
			(effects
				(font
					(size 1.27 1.27)
				)
				(justify mirror)
			)
		)
		(property "Value" ""
			(at 0 0 90)
			(layer "B.Fab")
			(effects
				(font
					(size 1.27 1.27)
				)
				(justify mirror)
			)
		)
		(duplicate_pad_numbers_are_jumpers no)
		(fp_line
			(start 0.7874 -0.4064)
			(end -0.7874 -0.4064)
			(stroke
				(width 0.1524)
				(type default)
			)
			(layer "B.SilkS")
		)
		(fp_line
			(start -0.7874 -0.4064)
			(end -0.7874 0.4064)
			(stroke
				(width 0.1524)
				(type default)
			)
			(layer "B.SilkS")
		)
		(fp_line
			(start 0.7874 0.4064)
			(end 0.7874 -0.4064)
			(stroke
				(width 0.1524)
				(type default)
			)
			(layer "B.SilkS")
		)
		(fp_line
			(start -0.7874 0.4064)
			(end 0.7874 0.4064)
			(stroke
				(width 0.1524)
				(type default)
			)
			(layer "B.SilkS")
		)
		(fp_line
			(start 0.67945 -0.305054)
			(end 0.12065 -0.305054)
			(stroke
				(width 0.1)
				(type default)
			)
			(layer "B.Fab")
		)
		(fp_line
			(start 0.12065 -0.305054)
			(end 0.12065 -0.2794)
			(stroke
				(width 0.1)
				(type default)
			)
			(layer "B.Fab")
		)
		(fp_line
			(start -0.12065 -0.3048)
			(end -0.67945 -0.3048)
			(stroke
				(width 0.1)
				(type default)
			)
			(layer "B.Fab")
		)
		(fp_line
			(start -0.67945 -0.3048)
			(end -0.67945 0.3048)
			(stroke
				(width 0.1)
				(type default)
			)
			(layer "B.Fab")
		)
		(fp_line
			(start 0.12065 -0.2794)
			(end -0.12065 -0.2794)
			(stroke
				(width 0.1)
				(type default)
			)
			(layer "B.Fab")
		)
		(fp_line
			(start -0.12065 -0.2794)
			(end -0.12065 -0.3048)
			(stroke
				(width 0.1)
				(type default)
			)
			(layer "B.Fab")
		)
		(fp_line
			(start 0.12065 0.2794)
			(end 0.12065 0.3048)
			(stroke
				(width 0.1)
				(type default)
			)
			(layer "B.Fab")
		)
		(fp_line
			(start -0.120396 0.2794)
			(end 0.12065 0.2794)
			(stroke
				(width 0.1)
				(type default)
			)
			(layer "B.Fab")
		)
		(fp_line
			(start 0.67945 0.3048)
			(end 0.67945 -0.305054)
			(stroke
				(width 0.1)
				(type default)
			)
			(layer "B.Fab")
		)
		(fp_line
			(start 0.12065 0.3048)
			(end 0.67945 0.3048)
			(stroke
				(width 0.1)
				(type default)
			)
			(layer "B.Fab")
		)
		(fp_line
			(start -0.120396 0.3048)
			(end -0.120396 0.2794)
			(stroke
				(width 0.1)
				(type default)
			)
			(layer "B.Fab")
		)
		(fp_line
			(start -0.67945 0.3048)
			(end -0.120396 0.3048)
			(stroke
				(width 0.1)
				(type default)
			)
			(layer "B.Fab")
		)
		(pad "1" smd circle
			(at 0.40005 0 270)
			(size 0 0)
			(layers "B.Cu" "B.Mask" "B.Paste")
			(net "P3V3_OCP_UV_2_R1")
		)
		(pad "2" smd circle
			(at -0.40005 0 270)
			(size 0 0)
			(layers "B.Cu" "B.Mask" "B.Paste")
			(net "P3V3_OCP_UV_2")
		)
	)
	(footprint ""
		(layer "B.Cu")
		(at 416.02914 -169.700194)
		(property "Reference" "PC197_P0_1"
			(at 0 0 0)
			(layer "B.SilkS")
			(hide yes)
			(effects
				(font
					(size 1.27 1.27)
				)
				(justify mirror)
			)
		)
		(property "Value" ""
			(at 0 0 0)
			(layer "B.Fab")
			(effects
				(font
					(size 1.27 1.27)
				)
				(justify mirror)
			)
		)
		(duplicate_pad_numbers_are_jumpers no)
		(fp_line
			(start -1.524 -0.762)
			(end -1.524 0.762)
			(stroke
				(width 0.1524)
				(type default)
			)
			(layer "B.SilkS")
		)
		(fp_line
			(start -1.524 0.762)
			(end 1.524 0.762)
			(stroke
				(width 0.1524)
				(type default)
			)
			(layer "B.SilkS")
		)
		(fp_line
			(start 1.524 -0.762)
			(end -1.524 -0.762)
			(stroke
				(width 0.1524)
				(type default)
			)
			(layer "B.SilkS")
		)
		(fp_line
			(start 1.524 0.762)
			(end 1.524 -0.762)
			(stroke
				(width 0.1524)
				(type default)
			)
			(layer "B.SilkS")
		)
		(fp_line
			(start -1.1049 -0.724916)
			(end 1.1049 -0.724916)
			(stroke
				(width 0.1)
				(type default)
			)
			(layer "B.Fab")
		)
		(fp_line
			(start -1.1049 0.724916)
			(end -1.1049 -0.724916)
			(stroke
				(width 0.1)
				(type default)
			)
			(layer "B.Fab")
		)
		(fp_line
			(start 1.1049 -0.724916)
			(end 1.1049 0.724916)
			(stroke
				(width 0.1)
				(type default)
			)
			(layer "B.Fab")
		)
		(fp_line
			(start 1.1049 0.724916)
			(end -1.1049 0.724916)
			(stroke
				(width 0.1)
				(type default)
			)
			(layer "B.Fab")
		)
		(pad "1" smd rect
			(at 0.889 0)
			(size 1.016 1.27)
			(layers "B.Cu" "B.Mask" "B.Paste")
			(net "SW_P12V_PVCCINFAON_CPU0_FLT")
		)
		(pad "2" smd rect
			(at -0.889 0)
			(size 1.016 1.27)
			(layers "B.Cu" "B.Mask" "B.Paste")
			(net "GND")
		)
	)
)
